FILE_TYPE = MACRO_DRAWING;
SET COLOR_WIRE YELLOW;
SET COLOR_PROP ORANGE;
SET COLOR_DOT WHITE;
SET COLOR_ARC YELLOW;
SET COLOR_BODY GREEN;
SET COLOR_NOTE PURPLE;
SET PROP_DISPLAY VALUE;
SET PAGE_NUMBER P62;
FORCEADD QUANTA_TITLE_BLOCK_C..1
(0 0);
FORCEPROP 1 LAST CUSTOM_TXT_CDS <NAME_2>
J 0
(-3175 50);
FORCEPROP 1 LAST CUSTOM_TXT_CDS <NAME_1>
J 0
(-3175 175);
FORCEPROP 1 LAST CUSTOM_TXT_CDS <Q_NUMBER>
J 0
(-1403 103);
DISPLAY 1.212766 (-1403 103);
FORCEPROP 1 LAST CUSTOM_TXT_CDS <Q_PROJ>
J 0
(-2382 102);
DISPLAY 1.212766 (-2382 102);
FORCEPROP 1 LAST CUSTOM_TXT_CDS <Q_REV>
J 0
(-184 103);
DISPLAY 1.212766 (-184 103);
FORCEPROP 1 LAST CUSTOM_TXT_CDS <CON_LAST_MODIFIED>
J 0
(-1885 15);
DISPLAY 0.978723 (-1885 15);
FORCEPROP 1 LAST CUSTOM_TXT_CDS <CON_PAGE_NUM> OF <CON_TOTAL_PAGES>
J 0
(-446 18);
DISPLAY 0.978723 (-446 18);
FORCEPROP 1 LAST Q_DEPT BU9
J 1
(-3763 49);
DISPLAY 1.957447 (-3763 49);
PAINT GREEN (-3763 49);
FORCEPROP 1 LAST Q_TITLE Blank
J 0
(-9366 26);
DISPLAY 2.446809 (-9366 26);
PAINT GREEN (-9366 26);
FORCEPROP 0 LAST CDS_CON_LAST_MODIFIED Wed Jul 21 11:34:55 2021
J 0
(-1885 15);
DISPLAY INVISIBLE (-1885 15);
FORCEPROP 2 LAST PAGE_BORDER TRUE
J 0
(-7890 5250);
DISPLAY 0.638298 (-7890 5250);
PAINT PINK (-7890 5250);
DISPLAY INVISIBLE (-7890 5250);
FORCEPROP 2 LAST CDS_LIB pure_quanta
J 0
(0 0);
DISPLAY INVISIBLE (0 0);
FORCEPROP 1 LAST CDS_LMAN_SYM_OUTLINE -9475,6775,100,-125
J 0
(0 0);
DISPLAY 0.468085 (0 0);
PAINT GREEN (0 0);
DISPLAY INVISIBLE (0 0);
FORCEPROP 1 LAST COMMENT_BODY TRUE
J 0
(12 -13);
DISPLAY 0.978723 (12 -13);
PAINT GREEN (12 -13);
DISPLAY INVISIBLE (12 -13);
FORCEPROP 2 LAST CUSTOM_TXT_CDS <XR_PAGE_TITLE>
J 0
(-7890 5250);
DISPLAY 0.638298 (-7890 5250);
PAINT PINK (-7890 5250);
DISPLAY INVISIBLE (-7890 5250);
FORCEPROP 2 LAST CDS_XR_PAGE_TITLE CR-62 : @T6G_MB_LIB.T6G(SCH_1):PAGE62
J 0
(-7890 5250);
DISPLAY 0.638298 (-7890 5250);
PAINT PINK (-7890 5250);
DISPLAY INVISIBLE (-7890 5250);
QUIT
